(kicad_pcb
	(version 20260206)
	(generator "pcbnew")
	(generator_version "10.0")
	(general
		(thickness 1.6)
		(legacy_teardrops no)
	)
	(paper "A4")
	(title_block
		(title "Wiwynn_Tioga_Pass_MB.brd")
		(comment 1 "Tioga Pass / footprints 4248-4255 of 4770")
	)
	(layers
		(0 "F.Cu" signal "TOP")
		(4 "In1.Cu" signal "L2GND")
		(6 "In2.Cu" signal "L3")
		(8 "In3.Cu" signal "L4GND")
		(10 "In4.Cu" signal "L5")
		(12 "In5.Cu" signal "L6GND")
		(14 "In6.Cu" signal "L7VCC")
		(16 "In7.Cu" signal "L8VCC")
		(18 "In8.Cu" signal "L9GND")
		(20 "In9.Cu" signal "L10")
		(22 "In10.Cu" signal "L11GND")
		(24 "In11.Cu" signal "L12")
		(26 "In12.Cu" signal "L13GND")
		(2 "B.Cu" signal "BOTTOM")
		(9 "F.Adhes" user "F.Adhesive")
		(11 "B.Adhes" user "B.Adhesive")
		(13 "F.Paste" user "Package Geometry/Pastemask Top")
		(15 "B.Paste" user "Package Geometry/Pastemask Bottom")
		(5 "F.SilkS" user "Ref Des/Silkscreen Top")
		(7 "B.SilkS" user "Ref Des/Silkscreen Bottom")
		(1 "F.Mask" user "Board Geometry/Soldermask Top")
		(3 "B.Mask" user "Board Geometry/Soldermask Bottom")
		(17 "Dwgs.User" user "User.Drawings")
		(19 "Cmts.User" user "User.Comments")
		(21 "Eco1.User" user "User.Eco1")
		(23 "Eco2.User" user "User.Eco2")
		(25 "Edge.Cuts" user "Board Geometry/Outline")
		(27 "Margin" user)
		(31 "F.CrtYd" user "Package Geometry/Place Bound Top")
		(29 "B.CrtYd" user "Package Geometry/Place Bound Bottom")
		(35 "F.Fab" user "Ref Des/Assembly Top")
		(33 "B.Fab" user "Ref Des/Assembly Bottom")
	)
	(footprint ""
		(layer "B.Cu")
		(at 194.564 -155.448)
		(property "Reference" "R6L1"
			(at 0 0 0)
			(layer "B.SilkS")
			(hide yes)
			(effects
				(font
					(size 1.27 1.27)
				)
				(justify mirror)
			)
		)
		(property "Value" ""
			(at 0 0 0)
			(layer "B.Fab")
			(effects
				(font
					(size 1.27 1.27)
				)
				(justify mirror)
			)
		)
		(duplicate_pad_numbers_are_jumpers no)
		(fp_poly
			(pts
				(xy 0.2794 -0.1016) (xy -0.2794 -0.1016) (xy -0.2794 0.9906) (xy 0.2794 0.9906)
			)
			(stroke
				(width 0)
				(type default)
			)
			(fill no)
			(layer "B.CrtYd")
		)
		(fp_line
			(start -0.2794 -0.1016)
			(end 0.2794 -0.1016)
			(stroke
				(width 0.1)
				(type default)
			)
			(layer "B.Fab")
		)
		(fp_line
			(start -0.2794 0.9906)
			(end -0.2794 -0.1016)
			(stroke
				(width 0.1)
				(type default)
			)
			(layer "B.Fab")
		)
		(fp_line
			(start 0.2794 -0.1016)
			(end 0.2794 0.9906)
			(stroke
				(width 0.1)
				(type default)
			)
			(layer "B.Fab")
		)
		(fp_line
			(start 0.2794 0.9906)
			(end -0.2794 0.9906)
			(stroke
				(width 0.1)
				(type default)
			)
			(layer "B.Fab")
		)
		(pad "1" smd rect
			(at 0 0 180)
			(size 0.508 0.508)
			(layers "B.Cu" "B.Mask" "B.Paste")
			(net "M_F_VREF")
		)
		(pad "2" smd rect
			(at 0 0.889 180)
			(size 0.508 0.508)
			(layers "B.Cu" "B.Mask" "B.Paste")
			(net "GND")
		)
		(zone
			(layer "B.Cu")
			(hatch none 0.5)
			(connect_pads
				(clearance 0)
			)
			(min_thickness 0.25)
			(keepout
				(tracks allowed)
				(vias not_allowed)
				(pads allowed)
				(copperpour not_allowed)
				(footprints allowed)
			)
			(placement
				(enabled no)
				(sheetname "")
			)
			(fill
				(thermal_gap 0.5)
				(thermal_bridge_width 0.5)
				(island_removal_mode 0)
			)
			(polygon
				(pts
					(xy 194.818 -155.194) (xy 194.31 -155.194) (xy 194.31 -154.813) (xy 194.818 -154.813)
				)
			)
		)
		(zone
			(layer "B.Cu")
			(hatch none 0.5)
			(connect_pads
				(clearance 0)
			)
			(min_thickness 0.25)
			(keepout
				(tracks not_allowed)
				(vias allowed)
				(pads allowed)
				(copperpour not_allowed)
				(footprints allowed)
			)
			(placement
				(enabled no)
				(sheetname "")
			)
			(fill
				(thermal_gap 0.5)
				(thermal_bridge_width 0.5)
				(island_removal_mode 0)
			)
			(polygon
				(pts
					(xy 194.818 -154.813) (xy 194.31 -154.813) (xy 194.31 -155.194) (xy 194.818 -155.194)
				)
			)
		)
	)
	(footprint ""
		(layer "B.Cu")
		(at 341.728806 -60.368434)
		(property "Reference" "R2U20"
			(at 0 0 0)
			(layer "B.SilkS")
			(hide yes)
			(effects
				(font
					(size 1.27 1.27)
				)
				(justify mirror)
			)
		)
		(property "Value" ""
			(at 0 0 0)
			(layer "B.Fab")
			(effects
				(font
					(size 1.27 1.27)
				)
				(justify mirror)
			)
		)
		(duplicate_pad_numbers_are_jumpers no)
		(fp_poly
			(pts
				(xy 0.2794 -0.1016) (xy -0.2794 -0.1016) (xy -0.2794 0.9906) (xy 0.2794 0.9906)
			)
			(stroke
				(width 0)
				(type default)
			)
			(fill no)
			(layer "B.CrtYd")
		)
		(fp_line
			(start -0.2794 -0.1016)
			(end 0.2794 -0.1016)
			(stroke
				(width 0.1)
				(type default)
			)
			(layer "B.Fab")
		)
		(fp_line
			(start -0.2794 0.9906)
			(end -0.2794 -0.1016)
			(stroke
				(width 0.1)
				(type default)
			)
			(layer "B.Fab")
		)
		(fp_line
			(start 0.2794 -0.1016)
			(end 0.2794 0.9906)
			(stroke
				(width 0.1)
				(type default)
			)
			(layer "B.Fab")
		)
		(fp_line
			(start 0.2794 0.9906)
			(end -0.2794 0.9906)
			(stroke
				(width 0.1)
				(type default)
			)
			(layer "B.Fab")
		)
		(pad "1" smd rect
			(at 0 0 180)
			(size 0.508 0.508)
			(layers "B.Cu" "B.Mask" "B.Paste")
			(net "P3E_CPU0_PE1_SS_RXP<3>")
		)
		(pad "2" smd rect
			(at 0 0.889 180)
			(size 0.508 0.508)
			(layers "B.Cu" "B.Mask" "B.Paste")
			(net "P3E_CPU0_PE1_SS_R_RXP<3>")
		)
		(zone
			(layer "B.Cu")
			(hatch none 0.5)
			(connect_pads
				(clearance 0)
			)
			(min_thickness 0.25)
			(keepout
				(tracks allowed)
				(vias not_allowed)
				(pads allowed)
				(copperpour not_allowed)
				(footprints allowed)
			)
			(placement
				(enabled no)
				(sheetname "")
			)
			(fill
				(thermal_gap 0.5)
				(thermal_bridge_width 0.5)
				(island_removal_mode 0)
			)
			(polygon
				(pts
					(xy 341.982806 -60.114434) (xy 341.474806 -60.114434) (xy 341.474806 -59.733434) (xy 341.982806 -59.733434)
				)
			)
		)
		(zone
			(layer "B.Cu")
			(hatch none 0.5)
			(connect_pads
				(clearance 0)
			)
			(min_thickness 0.25)
			(keepout
				(tracks not_allowed)
				(vias allowed)
				(pads allowed)
				(copperpour not_allowed)
				(footprints allowed)
			)
			(placement
				(enabled no)
				(sheetname "")
			)
			(fill
				(thermal_gap 0.5)
				(thermal_bridge_width 0.5)
				(island_removal_mode 0)
			)
			(polygon
				(pts
					(xy 341.982806 -59.733434) (xy 341.474806 -59.733434) (xy 341.474806 -60.114434) (xy 341.982806 -60.114434)
				)
			)
		)
	)
	(footprint ""
		(layer "B.Cu")
		(at 350.022414 -125.227842 -90)
		(property "Reference" "C3M12"
			(at 0 0 90)
			(layer "B.SilkS")
			(hide yes)
			(effects
				(font
					(size 1.27 1.27)
				)
				(justify mirror)
			)
		)
		(property "Value" ""
			(at 0 0 90)
			(layer "B.Fab")
			(effects
				(font
					(size 1.27 1.27)
				)
				(justify mirror)
			)
		)
		(duplicate_pad_numbers_are_jumpers no)
		(fp_poly
			(pts
				(xy -0.3048 -0.1016) (xy -0.3048 0.9906) (xy 0.3048 0.9906) (xy 0.3048 -0.1016)
			)
			(stroke
				(width 0)
				(type default)
			)
			(fill no)
			(layer "B.CrtYd")
		)
		(fp_line
			(start -0.3048 0.9906)
			(end -0.3048 -0.1016)
			(stroke
				(width 0.1)
				(type default)
			)
			(layer "B.Fab")
		)
		(fp_line
			(start 0.3048 0.9906)
			(end -0.3048 0.9906)
			(stroke
				(width 0.1)
				(type default)
			)
			(layer "B.Fab")
		)
		(fp_line
			(start -0.3048 -0.1016)
			(end 0.3048 -0.1016)
			(stroke
				(width 0.1)
				(type default)
			)
			(layer "B.Fab")
		)
		(fp_line
			(start 0.3048 -0.1016)
			(end 0.3048 0.9906)
			(stroke
				(width 0.1)
				(type default)
			)
			(layer "B.Fab")
		)
		(pad "1" smd rect
			(at 0 0 90)
			(size 0.508 0.508)
			(layers "B.Cu" "B.Mask" "B.Paste")
			(net "P3E_CPU0_PE1_PCH_R_RXN<14>")
		)
		(pad "2" smd rect
			(at 0 0.889 90)
			(size 0.508 0.508)
			(layers "B.Cu" "B.Mask" "B.Paste")
			(net "P3E_CPU0_PE1_PCH_RXN<14>")
		)
		(zone
			(layer "B.Cu")
			(hatch none 0.5)
			(connect_pads
				(clearance 0)
			)
			(min_thickness 0.25)
			(keepout
				(tracks not_allowed)
				(vias allowed)
				(pads allowed)
				(copperpour not_allowed)
				(footprints allowed)
			)
			(placement
				(enabled no)
				(sheetname "")
			)
			(fill
				(thermal_gap 0.5)
				(thermal_bridge_width 0.5)
				(island_removal_mode 0)
			)
			(polygon
				(pts
					(xy 349.387414 -124.973842) (xy 349.387414 -125.481842) (xy 349.768414 -125.481842) (xy 349.768414 -124.973842)
				)
			)
		)
		(zone
			(layer "B.Cu")
			(hatch none 0.5)
			(connect_pads
				(clearance 0)
			)
			(min_thickness 0.25)
			(keepout
				(tracks allowed)
				(vias not_allowed)
				(pads allowed)
				(copperpour not_allowed)
				(footprints allowed)
			)
			(placement
				(enabled no)
				(sheetname "")
			)
			(fill
				(thermal_gap 0.5)
				(thermal_bridge_width 0.5)
				(island_removal_mode 0)
			)
			(polygon
				(pts
					(xy 349.768414 -124.973842) (xy 349.768414 -125.481842) (xy 349.387414 -125.481842) (xy 349.387414 -124.973842)
				)
			)
		)
	)
	(footprint ""
		(layer "B.Cu")
		(at 474.938344 -5.70992 90)
		(property "Reference" "R2U39"
			(at 0 0 90)
			(layer "B.SilkS")
			(hide yes)
			(effects
				(font
					(size 1.27 1.27)
				)
				(justify mirror)
			)
		)
		(property "Value" ""
			(at 0 0 90)
			(layer "B.Fab")
			(effects
				(font
					(size 1.27 1.27)
				)
				(justify mirror)
			)
		)
		(duplicate_pad_numbers_are_jumpers no)
		(fp_poly
			(pts
				(xy 0.2794 -0.1016) (xy -0.2794 -0.1016) (xy -0.2794 0.9906) (xy 0.2794 0.9906)
			)
			(stroke
				(width 0)
				(type default)
			)
			(fill no)
			(layer "B.CrtYd")
		)
		(fp_line
			(start 0.2794 -0.1016)
			(end 0.2794 0.9906)
			(stroke
				(width 0.1)
				(type default)
			)
			(layer "B.Fab")
		)
		(fp_line
			(start -0.2794 -0.1016)
			(end 0.2794 -0.1016)
			(stroke
				(width 0.1)
				(type default)
			)
			(layer "B.Fab")
		)
		(fp_line
			(start 0.2794 0.9906)
			(end -0.2794 0.9906)
			(stroke
				(width 0.1)
				(type default)
			)
			(layer "B.Fab")
		)
		(fp_line
			(start -0.2794 0.9906)
			(end -0.2794 -0.1016)
			(stroke
				(width 0.1)
				(type default)
			)
			(layer "B.Fab")
		)
		(pad "1" smd rect
			(at 0 0 270)
			(size 0.508 0.508)
			(layers "B.Cu" "B.Mask" "B.Paste")
			(net "P3V3_STBY")
		)
		(pad "2" smd rect
			(at 0 0.889 270)
			(size 0.508 0.508)
			(layers "B.Cu" "B.Mask" "B.Paste")
			(net "SMB_SENSOR_STBY_LVC3_SDA")
		)
		(zone
			(layer "B.Cu")
			(hatch none 0.5)
			(connect_pads
				(clearance 0)
			)
			(min_thickness 0.25)
			(keepout
				(tracks allowed)
				(vias not_allowed)
				(pads allowed)
				(copperpour not_allowed)
				(footprints allowed)
			)
			(placement
				(enabled no)
				(sheetname "")
			)
			(fill
				(thermal_gap 0.5)
				(thermal_bridge_width 0.5)
				(island_removal_mode 0)
			)
			(polygon
				(pts
					(xy 475.192344 -5.96392) (xy 475.192344 -5.45592) (xy 475.573344 -5.45592) (xy 475.573344 -5.96392)
				)
			)
		)
		(zone
			(layer "B.Cu")
			(hatch none 0.5)
			(connect_pads
				(clearance 0)
			)
			(min_thickness 0.25)
			(keepout
				(tracks not_allowed)
				(vias allowed)
				(pads allowed)
				(copperpour not_allowed)
				(footprints allowed)
			)
			(placement
				(enabled no)
				(sheetname "")
			)
			(fill
				(thermal_gap 0.5)
				(thermal_bridge_width 0.5)
				(island_removal_mode 0)
			)
			(polygon
				(pts
					(xy 475.573344 -5.96392) (xy 475.573344 -5.45592) (xy 475.192344 -5.45592) (xy 475.192344 -5.96392)
				)
			)
		)
	)
	(footprint ""
		(layer "B.Cu")
		(at 421.513 -146.939 -90)
		(property "Reference" "C2L23"
			(at 0 0 90)
			(layer "B.SilkS")
			(hide yes)
			(effects
				(font
					(size 1.27 1.27)
				)
				(justify mirror)
			)
		)
		(property "Value" ""
			(at 0 0 90)
			(layer "B.Fab")
			(effects
				(font
					(size 1.27 1.27)
				)
				(justify mirror)
			)
		)
		(duplicate_pad_numbers_are_jumpers no)
		(fp_poly
			(pts
				(xy -0.3048 -0.1016) (xy -0.3048 0.9906) (xy 0.3048 0.9906) (xy 0.3048 -0.1016)
			)
			(stroke
				(width 0)
				(type default)
			)
			(fill no)
			(layer "B.CrtYd")
		)
		(fp_line
			(start -0.3048 0.9906)
			(end -0.3048 -0.1016)
			(stroke
				(width 0.1)
				(type default)
			)
			(layer "B.Fab")
		)
		(fp_line
			(start 0.3048 0.9906)
			(end -0.3048 0.9906)
			(stroke
				(width 0.1)
				(type default)
			)
			(layer "B.Fab")
		)
		(fp_line
			(start -0.3048 -0.1016)
			(end 0.3048 -0.1016)
			(stroke
				(width 0.1)
				(type default)
			)
			(layer "B.Fab")
		)
		(fp_line
			(start 0.3048 -0.1016)
			(end 0.3048 0.9906)
			(stroke
				(width 0.1)
				(type default)
			)
			(layer "B.Fab")
		)
		(pad "1" smd rect
			(at 0 0 90)
			(size 0.508 0.508)
			(layers "B.Cu" "B.Mask" "B.Paste")
			(net "SATA6G_P3_TX_C_DP")
		)
		(pad "2" smd rect
			(at 0 0.889 90)
			(size 0.508 0.508)
			(layers "B.Cu" "B.Mask" "B.Paste")
			(net "SATA6G_PCH_PCIE_UP_SATA_TXP<3>")
		)
		(zone
			(layer "B.Cu")
			(hatch none 0.5)
			(connect_pads
				(clearance 0)
			)
			(min_thickness 0.25)
			(keepout
				(tracks not_allowed)
				(vias allowed)
				(pads allowed)
				(copperpour not_allowed)
				(footprints allowed)
			)
			(placement
				(enabled no)
				(sheetname "")
			)
			(fill
				(thermal_gap 0.5)
				(thermal_bridge_width 0.5)
				(island_removal_mode 0)
			)
			(polygon
				(pts
					(xy 420.878 -146.685) (xy 420.878 -147.193) (xy 421.259 -147.193) (xy 421.259 -146.685)
				)
			)
		)
		(zone
			(layer "B.Cu")
			(hatch none 0.5)
			(connect_pads
				(clearance 0)
			)
			(min_thickness 0.25)
			(keepout
				(tracks allowed)
				(vias not_allowed)
				(pads allowed)
				(copperpour not_allowed)
				(footprints allowed)
			)
			(placement
				(enabled no)
				(sheetname "")
			)
			(fill
				(thermal_gap 0.5)
				(thermal_bridge_width 0.5)
				(island_removal_mode 0)
			)
			(polygon
				(pts
					(xy 421.259 -146.685) (xy 421.259 -147.193) (xy 420.878 -147.193) (xy 420.878 -146.685)
				)
			)
		)
	)
	(footprint ""
		(layer "B.Cu")
		(at 168.402 -128.905 90)
		(property "Reference" "U6M1"
			(at 0.14986 2.838958 90)
			(unlocked yes)
			(layer "B.SilkS")
			(effects
				(font
					(size 0.7874 0.5842)
					(thickness 0.1524)
				)
				(justify left mirror)
			)
		)
		(property "Value" ""
			(at 0 0 90)
			(layer "B.Fab")
			(effects
				(font
					(size 1.27 1.27)
				)
				(justify mirror)
			)
		)
		(duplicate_pad_numbers_are_jumpers no)
		(fp_circle
			(center 0.931418 -0.008382)
			(end 0.931418 0.118618)
			(stroke
				(width 0.254)
				(type default)
			)
			(fill no)
			(layer "B.SilkS")
		)
		(fp_poly
			(pts
				(xy -0.21463 -0.450088) (xy -1.56337 -0.450088) (xy -1.56337 1.75006) (xy -0.21463 1.75006)
			)
			(stroke
				(width 0)
				(type default)
			)
			(fill no)
			(layer "B.CrtYd")
		)
		(fp_line
			(start -0.21463 -0.450088)
			(end -1.56337 -0.450088)
			(stroke
				(width 0.1)
				(type default)
			)
			(layer "B.Fab")
		)
		(fp_line
			(start -1.56337 -0.450088)
			(end -1.56337 1.75006)
			(stroke
				(width 0.1)
				(type default)
			)
			(layer "B.Fab")
		)
		(fp_line
			(start -0.21463 1.75006)
			(end -0.21463 -0.450088)
			(stroke
				(width 0.1)
				(type default)
			)
			(layer "B.Fab")
		)
		(fp_line
			(start -1.56337 1.75006)
			(end -0.21463 1.75006)
			(stroke
				(width 0.1)
				(type default)
			)
			(layer "B.Fab")
		)
		(fp_circle
			(center 0.4699 -0.8382)
			(end 0.4699 -0.7112)
			(stroke
				(width 0.254)
				(type default)
			)
			(fill no)
			(layer "B.Fab")
		)
		(pad "1" smd rect
			(at 0 0 270)
			(size 1.016 0.381)
			(layers "B.Cu" "B.Mask" "B.Paste")
			(net "FM_CPU1_PKGID1")
		)
		(pad "2" smd rect
			(at 0 0.649986 270)
			(size 1.016 0.381)
			(layers "B.Cu" "B.Mask" "B.Paste")
			(net "P1V8_MCP_CPU1")
		)
		(pad "3" smd rect
			(at 0 1.299972 270)
			(size 1.016 0.381)
			(layers "B.Cu" "B.Mask" "B.Paste")
			(net "GND")
		)
		(pad "4" smd rect
			(at -1.778 1.299972 270)
			(size 1.016 0.381)
			(layers "B.Cu" "B.Mask" "B.Paste")
			(net "JTAG_MCP_CPU1_TDI_R")
		)
		(pad "5" smd rect
			(at -1.778 0 270)
			(size 1.016 0.381)
			(layers "B.Cu" "B.Mask" "B.Paste")
			(net "P3V3_STBY")
		)
	)
	(footprint ""
		(layer "B.Cu")
		(at 385.7625 -60.198 -90)
		(property "Reference" "R2R12"
			(at 0 0 90)
			(layer "B.SilkS")
			(hide yes)
			(effects
				(font
					(size 1.27 1.27)
				)
				(justify mirror)
			)
		)
		(property "Value" ""
			(at 0 0 90)
			(layer "B.Fab")
			(effects
				(font
					(size 1.27 1.27)
				)
				(justify mirror)
			)
		)
		(duplicate_pad_numbers_are_jumpers no)
		(fp_poly
			(pts
				(xy 0.2794 -0.1016) (xy -0.2794 -0.1016) (xy -0.2794 0.9906) (xy 0.2794 0.9906)
			)
			(stroke
				(width 0)
				(type default)
			)
			(fill no)
			(layer "B.CrtYd")
		)
		(fp_line
			(start -0.2794 0.9906)
			(end -0.2794 -0.1016)
			(stroke
				(width 0.1)
				(type default)
			)
			(layer "B.Fab")
		)
		(fp_line
			(start 0.2794 0.9906)
			(end -0.2794 0.9906)
			(stroke
				(width 0.1)
				(type default)
			)
			(layer "B.Fab")
		)
		(fp_line
			(start -0.2794 -0.1016)
			(end 0.2794 -0.1016)
			(stroke
				(width 0.1)
				(type default)
			)
			(layer "B.Fab")
		)
		(fp_line
			(start 0.2794 -0.1016)
			(end 0.2794 0.9906)
			(stroke
				(width 0.1)
				(type default)
			)
			(layer "B.Fab")
		)
		(pad "1" smd rect
			(at 0 0 90)
			(size 0.508 0.508)
			(layers "B.Cu" "B.Mask" "B.Paste")
			(net "SPI_PCH_IO2")
		)
		(pad "2" smd rect
			(at 0 0.889 90)
			(size 0.508 0.508)
			(layers "B.Cu" "B.Mask" "B.Paste")
			(net "SPI_PCH_IO2_R1")
		)
		(zone
			(layer "B.Cu")
			(hatch none 0.5)
			(connect_pads
				(clearance 0)
			)
			(min_thickness 0.25)
			(keepout
				(tracks not_allowed)
				(vias allowed)
				(pads allowed)
				(copperpour not_allowed)
				(footprints allowed)
			)
			(placement
				(enabled no)
				(sheetname "")
			)
			(fill
				(thermal_gap 0.5)
				(thermal_bridge_width 0.5)
				(island_removal_mode 0)
			)
			(polygon
				(pts
					(xy 385.1275 -59.944) (xy 385.1275 -60.452) (xy 385.5085 -60.452) (xy 385.5085 -59.944)
				)
			)
		)
		(zone
			(layer "B.Cu")
			(hatch none 0.5)
			(connect_pads
				(clearance 0)
			)
			(min_thickness 0.25)
			(keepout
				(tracks allowed)
				(vias not_allowed)
				(pads allowed)
				(copperpour not_allowed)
				(footprints allowed)
			)
			(placement
				(enabled no)
				(sheetname "")
			)
			(fill
				(thermal_gap 0.5)
				(thermal_bridge_width 0.5)
				(island_removal_mode 0)
			)
			(polygon
				(pts
					(xy 385.5085 -59.944) (xy 385.5085 -60.452) (xy 385.1275 -60.452) (xy 385.1275 -59.944)
				)
			)
		)
	)
	(footprint ""
		(layer "B.Cu")
		(at 353.64801 -143.629888 90)
		(property "Reference" "C7W10"
			(at 0 0 90)
			(layer "B.SilkS")
			(hide yes)
			(effects
				(font
					(size 1.27 1.27)
				)
				(justify mirror)
			)
		)
		(property "Value" "*"
			(at 0.0762 -6.2357 90)
			(unlocked yes)
			(layer "B.Fab")
			(hide yes)
			(effects
				(font
					(size 1.27 1.016)
					(thickness 0.1524)
				)
				(justify mirror)
			)
		)
		(property "Device Type" "SC22U16V5MX-4-GP_SMD-BCG5-SC22A"
			(at 0.0762 -8.2677 90)
			(unlocked yes)
			(layer "B.Fab")
			(hide yes)
			(effects
				(font
					(size 1.27 1.016)
					(thickness 0.1524)
				)
				(justify mirror)
			)
		)
		(duplicate_pad_numbers_are_jumpers no)
		(fp_line
			(start -0.635 0)
			(end 0.635 0)
			(stroke
				(width 0.508)
				(type default)
			)
			(layer "B.SilkS")
		)
		(fp_rect
			(start 0.9652 1.778)
			(end -0.9652 -1.778)
			(stroke
				(width 0)
				(type default)
			)
			(fill no)
			(layer "B.CrtYd")
		)
		(fp_poly
			(pts
				(xy 0.9652 -1.778) (xy -0.9652 -1.778) (xy -0.9652 1.778) (xy 0.9652 1.778)
			)
			(stroke
				(width 0)
				(type default)
			)
			(fill no)
			(layer "B.Fab")
		)
		(pad "1" smd rect
			(at 0 -0.9652 270)
			(size 1.397 1.143)
			(layers "B.Cu" "B.Mask" "B.Paste")
			(net "VR_FET_SW_P12V_STBY_PVDDQ_DEF")
		)
		(pad "2" smd rect
			(at 0 0.9652 270)
			(size 1.397 1.143)
			(layers "B.Cu" "B.Mask" "B.Paste")
			(net "GND")
		)
	)
)
